(kicad_pcb
	(version 20260206)
	(generator "pcbnew")
	(generator_version "10.0")
	(general
		(thickness 1.6)
		(legacy_teardrops no)
	)
	(paper "A4")
	(title_block
		(title "Bryce Canyon_F.DPB_16315-1-OCP.brd")
		(comment 1 "Bryce Canyon / footprints 1320-1327 of 2223")
	)
	(layers
		(0 "F.Cu" signal "TOP")
		(4 "In1.Cu" signal "L2GND")
		(6 "In2.Cu" signal "L3")
		(8 "In3.Cu" signal "L4GND")
		(10 "In4.Cu" signal "L5")
		(12 "In5.Cu" signal "L6VCC")
		(14 "In6.Cu" signal "L7VCC")
		(16 "In7.Cu" signal "L8")
		(18 "In8.Cu" signal "L9GND")
		(20 "In9.Cu" signal "L10")
		(22 "In10.Cu" signal "L11GND")
		(2 "B.Cu" signal "BOTTOM")
		(9 "F.Adhes" user "F.Adhesive")
		(11 "B.Adhes" user "B.Adhesive")
		(13 "F.Paste" user "Package Geometry/Pastemask Top")
		(15 "B.Paste" user "Package Geometry/Pastemask Bottom")
		(5 "F.SilkS" user "Ref Des/Silkscreen Top")
		(7 "B.SilkS" user "Ref Des/Silkscreen Bottom")
		(1 "F.Mask" user "Board Geometry/Soldermask Top")
		(3 "B.Mask" user "Board Geometry/Soldermask Bottom")
		(17 "Dwgs.User" user "User.Drawings")
		(19 "Cmts.User" user "User.Comments")
		(21 "Eco1.User" user "User.Eco1")
		(23 "Eco2.User" user "User.Eco2")
		(25 "Edge.Cuts" user "Board Geometry/Outline")
		(27 "Margin" user)
		(31 "F.CrtYd" user "Package Geometry/Place Bound Top")
		(29 "B.CrtYd" user "Package Geometry/Place Bound Bottom")
		(35 "F.Fab" user "Ref Des/Assembly Top")
		(33 "B.Fab" user "Ref Des/Assembly Bottom")
	)
	(footprint ""
		(layer "F.Cu")
		(at 339.47227 -245.31955 -90)
		(property "Reference" "R480"
			(at 0 0 270)
			(layer "F.SilkS")
			(hide yes)
			(effects
				(font
					(size 1.27 1.27)
				)
			)
		)
		(property "Value" "4K7R2J-2-GP"
			(at 0.064008 -3.993896 270)
			(unlocked yes)
			(layer "F.Fab")
			(hide yes)
			(effects
				(font
					(size 1.016 1.016)
					(thickness 0.1524)
				)
			)
		)
		(property "Device Type" "R402H16"
			(at 0.064008 -5.517896 270)
			(unlocked yes)
			(layer "F.Fab")
			(hide yes)
			(effects
				(font
					(size 1.016 1.016)
					(thickness 0.1524)
				)
			)
		)
		(duplicate_pad_numbers_are_jumpers no)
		(fp_line
			(start -0.508 -0.9398)
			(end -0.508 0.9398)
			(stroke
				(width 0.1524)
				(type default)
			)
			(layer "F.SilkS")
		)
		(fp_line
			(start 0.508 -0.9398)
			(end -0.508 -0.9398)
			(stroke
				(width 0.1524)
				(type default)
			)
			(layer "F.SilkS")
		)
		(fp_rect
			(start -0.508 0.9398)
			(end 0.508 -0.9398)
			(stroke
				(width 0)
				(type default)
			)
			(fill no)
			(layer "F.CrtYd")
		)
		(fp_rect
			(start -0.508 0.9398)
			(end 0.508 -0.9398)
			(stroke
				(width 0)
				(type default)
			)
			(fill no)
			(layer "F.Fab")
		)
		(pad "1" smd custom
			(at 0 -0.4445 270)
			(size 0.1397 0.1397)
			(layers "F.Cu" "F.Mask" "F.Paste")
			(net "DRIVE_A_7_ACT")
			(options
				(clearance outline)
				(anchor circle)
			)
			(primitives
				(gr_poly
					(pts
						(arc
							(start -0.1778 -0.2794)
							(mid -0.249642 -0.249642)
							(end -0.2794 -0.1778)
						)
						(arc
							(start -0.2794 0.1778)
							(mid -0.249642 0.249642)
							(end -0.1778 0.2794)
						)
						(arc
							(start 0.1778 0.2794)
							(mid 0.249642 0.249642)
							(end 0.2794 0.1778)
						)
						(arc
							(start 0.2794 -0.1778)
							(mid 0.249642 -0.249642)
							(end 0.1778 -0.2794)
						)
					)
					(width 0)
					(fill yes)
				)
			)
		)
		(pad "2" smd custom
			(at 0 0.4445 270)
			(size 0.1397 0.1397)
			(layers "F.Cu" "F.Mask" "F.Paste")
			(net "GND")
			(options
				(clearance outline)
				(anchor circle)
			)
			(primitives
				(gr_poly
					(pts
						(arc
							(start -0.1778 -0.2794)
							(mid -0.249642 -0.249642)
							(end -0.2794 -0.1778)
						)
						(arc
							(start -0.2794 0.1778)
							(mid -0.249642 0.249642)
							(end -0.1778 0.2794)
						)
						(arc
							(start 0.1778 0.2794)
							(mid 0.249642 0.249642)
							(end 0.2794 0.1778)
						)
						(arc
							(start 0.2794 -0.1778)
							(mid 0.249642 -0.249642)
							(end 0.1778 -0.2794)
						)
					)
					(width 0)
					(fill yes)
				)
			)
		)
	)
	(footprint ""
		(layer "F.Cu")
		(at 298.91609 -155.684728 180)
		(property "Reference" "R994"
			(at 0 0 180)
			(layer "F.SilkS")
			(hide yes)
			(effects
				(font
					(size 1.27 1.27)
				)
			)
		)
		(property "Value" "100KR2F-L1-GP"
			(at 0.064008 -3.993896 180)
			(unlocked yes)
			(layer "F.Fab")
			(hide yes)
			(effects
				(font
					(size 1.016 1.016)
					(thickness 0.1524)
				)
			)
		)
		(property "Device Type" "R402H16"
			(at 0.064008 -5.517896 180)
			(unlocked yes)
			(layer "F.Fab")
			(hide yes)
			(effects
				(font
					(size 1.016 1.016)
					(thickness 0.1524)
				)
			)
		)
		(duplicate_pad_numbers_are_jumpers no)
		(fp_line
			(start 0.508 -0.9398)
			(end -0.508 -0.9398)
			(stroke
				(width 0.1524)
				(type default)
			)
			(layer "F.SilkS")
		)
		(fp_line
			(start -0.508 -0.9398)
			(end -0.508 0.9398)
			(stroke
				(width 0.1524)
				(type default)
			)
			(layer "F.SilkS")
		)
		(fp_rect
			(start -0.508 0.9398)
			(end 0.508 -0.9398)
			(stroke
				(width 0)
				(type default)
			)
			(fill no)
			(layer "F.CrtYd")
		)
		(fp_rect
			(start -0.508 0.9398)
			(end 0.508 -0.9398)
			(stroke
				(width 0)
				(type default)
			)
			(fill no)
			(layer "F.Fab")
		)
		(pad "1" smd custom
			(at 0 -0.4445 180)
			(size 0.1397 0.1397)
			(layers "F.Cu" "F.Mask" "F.Paste")
			(net "PCIE_COMP_B_TO_IOM_B_RST_2")
			(options
				(clearance outline)
				(anchor circle)
			)
			(primitives
				(gr_poly
					(pts
						(arc
							(start -0.1778 -0.2794)
							(mid -0.249642 -0.249642)
							(end -0.2794 -0.1778)
						)
						(arc
							(start -0.2794 0.1778)
							(mid -0.249642 0.249642)
							(end -0.1778 0.2794)
						)
						(arc
							(start 0.1778 0.2794)
							(mid 0.249642 0.249642)
							(end 0.2794 0.1778)
						)
						(arc
							(start 0.2794 -0.1778)
							(mid 0.249642 -0.249642)
							(end 0.1778 -0.2794)
						)
					)
					(width 0)
					(fill yes)
				)
			)
		)
		(pad "2" smd custom
			(at 0 0.4445 180)
			(size 0.1397 0.1397)
			(layers "F.Cu" "F.Mask" "F.Paste")
			(net "GND")
			(options
				(clearance outline)
				(anchor circle)
			)
			(primitives
				(gr_poly
					(pts
						(arc
							(start -0.1778 -0.2794)
							(mid -0.249642 -0.249642)
							(end -0.2794 -0.1778)
						)
						(arc
							(start -0.2794 0.1778)
							(mid -0.249642 0.249642)
							(end -0.1778 0.2794)
						)
						(arc
							(start 0.1778 0.2794)
							(mid 0.249642 0.249642)
							(end 0.2794 0.1778)
						)
						(arc
							(start 0.2794 -0.1778)
							(mid 0.249642 -0.249642)
							(end 0.1778 -0.2794)
						)
					)
					(width 0)
					(fill yes)
				)
			)
		)
	)
	(footprint ""
		(layer "F.Cu")
		(at 333.57185 -69.434964 -90)
		(property "Reference" "R821"
			(at 0 0 270)
			(layer "F.SilkS")
			(hide yes)
			(effects
				(font
					(size 1.27 1.27)
				)
			)
		)
		(property "Value" "2R6F-GP"
			(at -0.0508 -4.8514 270)
			(unlocked yes)
			(layer "F.Fab")
			(hide yes)
			(effects
				(font
					(size 1.016 1.016)
					(thickness 0.1524)
				)
			)
		)
		(property "Device Type" "R1206H26"
			(at 0 -6.3754 270)
			(unlocked yes)
			(layer "F.Fab")
			(hide yes)
			(effects
				(font
					(size 1.016 1.016)
					(thickness 0.1524)
				)
			)
		)
		(duplicate_pad_numbers_are_jumpers no)
		(fp_line
			(start -1.016 2.2352)
			(end -1.016 -2.2352)
			(stroke
				(width 0.1524)
				(type default)
			)
			(layer "F.SilkS")
		)
		(fp_line
			(start 1.016 2.2352)
			(end -1.016 2.2352)
			(stroke
				(width 0.1524)
				(type default)
			)
			(layer "F.SilkS")
		)
		(fp_line
			(start -1.016 -2.2352)
			(end 1.016 -2.2352)
			(stroke
				(width 0.1524)
				(type default)
			)
			(layer "F.SilkS")
		)
		(fp_line
			(start 1.016 -2.2352)
			(end 1.016 2.2352)
			(stroke
				(width 0.1524)
				(type default)
			)
			(layer "F.SilkS")
		)
		(fp_rect
			(start -1.0922 2.3114)
			(end 1.0922 -2.3114)
			(stroke
				(width 0)
				(type default)
			)
			(fill no)
			(layer "F.CrtYd")
		)
		(fp_poly
			(pts
				(xy -1.0922 -2.3114) (xy 1.0922 -2.3114) (xy 1.0922 2.3114) (xy -1.0922 2.3114)
			)
			(stroke
				(width 0)
				(type default)
			)
			(fill no)
			(layer "F.Fab")
		)
		(pad "1" smd rect
			(at 0 -1.397 270)
			(size 1.651 1.27)
			(layers "F.Cu" "F.Mask" "F.Paste")
			(net "P12V_HDD30")
		)
		(pad "2" smd rect
			(at 0 1.397 270)
			(size 1.651 1.27)
			(layers "F.Cu" "F.Mask" "F.Paste")
			(net "12V_PRE_30")
		)
	)
	(footprint ""
		(layer "F.Cu")
		(at 79.974948 -46.649894 180)
		(property "Reference" "D26"
			(at 0 0 180)
			(layer "F.SilkS")
			(hide yes)
			(effects
				(font
					(size 1.27 1.27)
				)
			)
		)
		(property "Value" "RB551V30-GP"
			(at 0 -6.7818 180)
			(unlocked yes)
			(layer "F.Fab")
			(hide yes)
			(effects
				(font
					(size 1.016 1.016)
					(thickness 0.1524)
				)
			)
		)
		(property "Device Type" "SOD323AKH38"
			(at 0 -8.6868 180)
			(unlocked yes)
			(layer "F.Fab")
			(hide yes)
			(effects
				(font
					(size 1.016 1.016)
					(thickness 0.1524)
				)
			)
		)
		(duplicate_pad_numbers_are_jumpers no)
		(fp_line
			(start 0.889 2.159)
			(end -0.889 2.159)
			(stroke
				(width 0.1524)
				(type default)
			)
			(layer "F.SilkS")
		)
		(fp_line
			(start 0.889 -1.9304)
			(end 0.889 2.159)
			(stroke
				(width 0.1524)
				(type default)
			)
			(layer "F.SilkS")
		)
		(fp_line
			(start 0.762 2.0574)
			(end -0.762 2.0574)
			(stroke
				(width 0.508)
				(type default)
			)
			(layer "F.SilkS")
		)
		(fp_line
			(start -0.889 2.159)
			(end -0.889 -1.9304)
			(stroke
				(width 0.1524)
				(type default)
			)
			(layer "F.SilkS")
		)
		(fp_line
			(start -0.889 -1.9304)
			(end 0.889 -1.9304)
			(stroke
				(width 0.1524)
				(type default)
			)
			(layer "F.SilkS")
		)
		(fp_rect
			(start -1.016 2.3114)
			(end 1.016 -2.0066)
			(stroke
				(width 0)
				(type default)
			)
			(fill no)
			(layer "F.CrtYd")
		)
		(fp_poly
			(pts
				(xy -1.016 -2.0066) (xy 1.016 -2.0066) (xy 1.016 2.3114) (xy -1.016 2.3114)
			)
			(stroke
				(width 0)
				(type default)
			)
			(fill no)
			(layer "F.Fab")
		)
		(pad "A" smd rect
			(at 0 -1.143 180)
			(size 0.5588 1.016)
			(layers "F.Cu" "F.Mask" "F.Paste")
			(net "SW_HDD_R26")
		)
		(pad "K" smd rect
			(at 0 1.143 180)
			(size 0.5588 1.016)
			(layers "F.Cu" "F.Mask" "F.Paste")
			(net "SW_HDD_N26")
		)
	)
	(footprint ""
		(layer "F.Cu")
		(at 224.546922 -155.42387 -90)
		(property "Reference" "TP210"
			(at 0 0 270)
			(layer "F.SilkS")
			(hide yes)
			(effects
				(font
					(size 1.27 1.27)
				)
			)
		)
		(property "Value" "TPAD32-GP"
			(at -0.0508 -1.6764 270)
			(unlocked yes)
			(layer "F.Fab")
			(hide yes)
			(effects
				(font
					(size 1.016 1.016)
					(thickness 0.1524)
				)
			)
		)
		(property "Device Type" "TPAD32"
			(at -0.0508 -3.2004 270)
			(unlocked yes)
			(layer "F.Fab")
			(hide yes)
			(effects
				(font
					(size 1.016 1.016)
					(thickness 0.1524)
				)
			)
		)
		(duplicate_pad_numbers_are_jumpers no)
		(fp_poly
			(pts
				(arc
					(start 0 -0.4064)
					(mid 0 0.4064)
					(end 0 -0.4064)
				)
			)
			(stroke
				(width 0)
				(type default)
			)
			(fill no)
			(layer "F.CrtYd")
		)
		(fp_poly
			(pts
				(arc
					(start 0 -0.7112)
					(mid 0 0.7112)
					(end 0 -0.7112)
				)
			)
			(stroke
				(width 0)
				(type default)
			)
			(fill no)
			(layer "F.Fab")
		)
		(pad "1" smd circle
			(at 0 0 270)
			(size 0.8128 0.8128)
			(layers "F.Cu" "F.Mask" "F.Paste")
			(net "TP_COMP_A_KR_P0_TX_DN")
		)
	)
	(footprint ""
		(layer "F.Cu")
		(at 267.00099 -145.858738 90)
		(property "Reference" "TP227"
			(at 0 0 90)
			(layer "F.SilkS")
			(hide yes)
			(effects
				(font
					(size 1.27 1.27)
				)
			)
		)
		(property "Value" "TPAD32-GP"
			(at -0.0508 -1.6764 90)
			(unlocked yes)
			(layer "F.Fab")
			(hide yes)
			(effects
				(font
					(size 1.016 1.016)
					(thickness 0.1524)
				)
			)
		)
		(property "Device Type" "TPAD32"
			(at -0.0508 -3.2004 90)
			(unlocked yes)
			(layer "F.Fab")
			(hide yes)
			(effects
				(font
					(size 1.016 1.016)
					(thickness 0.1524)
				)
			)
		)
		(duplicate_pad_numbers_are_jumpers no)
		(fp_poly
			(pts
				(arc
					(start 0 0.4064)
					(mid 0 -0.4064)
					(end 0 0.4064)
				)
			)
			(stroke
				(width 0)
				(type default)
			)
			(fill no)
			(layer "F.CrtYd")
		)
		(fp_poly
			(pts
				(arc
					(start 0 0.7112)
					(mid 0 -0.7112)
					(end 0 0.7112)
				)
			)
			(stroke
				(width 0)
				(type default)
			)
			(fill no)
			(layer "F.Fab")
		)
		(pad "1" smd circle
			(at 0 0 90)
			(size 0.8128 0.8128)
			(layers "F.Cu" "F.Mask" "F.Paste")
			(net "TP_SMB_COMP_B_NIC_SDA")
		)
	)
	(footprint ""
		(layer "F.Cu")
		(at 282.0162 12.2936 90)
		(property "Reference" "C108"
			(at 0 0 90)
			(layer "F.SilkS")
			(hide yes)
			(effects
				(font
					(size 1.27 1.27)
				)
			)
		)
		(property "Value" "SC1U16V3KX-5GP"
			(at 0 -2.8194 90)
			(unlocked yes)
			(layer "F.Fab")
			(hide yes)
			(effects
				(font
					(size 1.016 1.016)
					(thickness 0.1524)
				)
			)
		)
		(property "Device Type" "C603H36"
			(at 0 -4.3434 90)
			(unlocked yes)
			(layer "F.Fab")
			(hide yes)
			(effects
				(font
					(size 1.016 1.016)
					(thickness 0.1524)
				)
			)
		)
		(duplicate_pad_numbers_are_jumpers no)
		(fp_line
			(start 0.508 0)
			(end -0.508 0)
			(stroke
				(width 0.2032)
				(type default)
			)
			(layer "F.SilkS")
		)
		(fp_rect
			(start -0.5842 1.3335)
			(end 0.5842 -1.3335)
			(stroke
				(width 0)
				(type default)
			)
			(fill no)
			(layer "F.CrtYd")
		)
		(fp_rect
			(start -0.5842 1.3335)
			(end 0.5842 -1.3335)
			(stroke
				(width 0)
				(type default)
			)
			(fill no)
			(layer "F.Fab")
		)
		(pad "1" smd custom
			(at 0 -0.762 90)
			(size 0.2159 0.2159)
			(layers "F.Cu" "F.Mask" "F.Paste")
			(net "P3V3_BIAS")
			(options
				(clearance outline)
				(anchor circle)
			)
			(primitives
				(gr_poly
					(pts
						(arc
							(start -0.3302 -0.4318)
							(mid -0.402042 -0.402042)
							(end -0.4318 -0.3302)
						)
						(arc
							(start -0.4318 0.3302)
							(mid -0.402042 0.402042)
							(end -0.3302 0.4318)
						)
						(arc
							(start 0.3302 0.4318)
							(mid 0.402042 0.402042)
							(end 0.4318 0.3302)
						)
						(arc
							(start 0.4318 -0.3302)
							(mid 0.402042 -0.402042)
							(end 0.3302 -0.4318)
						)
					)
					(width 0)
					(fill yes)
				)
			)
		)
		(pad "2" smd custom
			(at 0 0.762 90)
			(size 0.2159 0.2159)
			(layers "F.Cu" "F.Mask" "F.Paste")
			(net "GND")
			(options
				(clearance outline)
				(anchor circle)
			)
			(primitives
				(gr_poly
					(pts
						(arc
							(start -0.3302 -0.4318)
							(mid -0.402042 -0.402042)
							(end -0.4318 -0.3302)
						)
						(arc
							(start -0.4318 0.3302)
							(mid -0.402042 0.402042)
							(end -0.3302 0.4318)
						)
						(arc
							(start 0.3302 0.4318)
							(mid 0.402042 0.402042)
							(end 0.4318 0.3302)
						)
						(arc
							(start 0.4318 -0.3302)
							(mid 0.402042 -0.402042)
							(end 0.3302 -0.4318)
						)
					)
					(width 0)
					(fill yes)
				)
			)
		)
	)
	(footprint ""
		(layer "F.Cu")
		(at 266.999974 -142.840964 90)
		(property "Reference" "TP242"
			(at 0 0 90)
			(layer "F.SilkS")
			(hide yes)
			(effects
				(font
					(size 1.27 1.27)
				)
			)
		)
		(property "Value" "TPAD32-GP"
			(at -0.0508 -1.6764 90)
			(unlocked yes)
			(layer "F.Fab")
			(hide yes)
			(effects
				(font
					(size 1.016 1.016)
					(thickness 0.1524)
				)
			)
		)
		(property "Device Type" "TPAD32"
			(at -0.0508 -3.2004 90)
			(unlocked yes)
			(layer "F.Fab")
			(hide yes)
			(effects
				(font
					(size 1.016 1.016)
					(thickness 0.1524)
				)
			)
		)
		(duplicate_pad_numbers_are_jumpers no)
		(fp_poly
			(pts
				(arc
					(start 0 0.4064)
					(mid 0 -0.4064)
					(end 0 0.4064)
				)
			)
			(stroke
				(width 0)
				(type default)
			)
			(fill no)
			(layer "F.CrtYd")
		)
		(fp_poly
			(pts
				(arc
					(start 0 0.7112)
					(mid 0 -0.7112)
					(end 0 0.7112)
				)
			)
			(stroke
				(width 0)
				(type default)
			)
			(fill no)
			(layer "F.Fab")
		)
		(pad "1" smd circle
			(at 0 0 90)
			(size 0.8128 0.8128)
			(layers "F.Cu" "F.Mask" "F.Paste")
			(net "TP_SMB_COMP_B_NIC_ALERT_N")
		)
	)
)
